#ISCELL
  mstr_misc dns *
  *
#ISCELL
  pure_quanta quanta_title_block_c *
  *
#ISCELL
  standard offpage *
  page75_i1
#CELL
  pure_quanta q_res *
  page75_i12
#ISCELL
  pure_quanta_power universal_gnd *
  page75_i15
#ISCELL
  standard offpage *
  page75_i27
#ISCELL
  standard offpage *
  page75_i28
#ISCELL
  standard offpage *
  page75_i3
#ISCELL
  standard offpage *
  page75_i32
#ISCELL
  standard offpage *
  page75_i33
#ISCELL
  standard offpage *
  page75_i35
#ISCELL
  pure_quanta_power universal_power *
  page75_i39
#ISCELL
  standard offpage *
  page75_i4
#CELL
  pure_quanta q_res *
  page75_i41
#CELL
  pure_quanta q_res *
  page75_i43
#CELL
  pure_quanta q_res *
  page75_i44
#CELL
  pure_quanta q_res *
  page75_i45
#CELL
  pure_quanta q_res *
  page75_i46
#ISCELL
  standard offpage *
  page75_i5
#ISCELL
  standard offpage *
  page75_i7
#CELL
  pure_quanta q_res *
  page75_i74
#CELL
  pure_quanta q_res *
  page75_i75
#CELL
  pure_quanta q_res *
  page75_i8
#ISCELL
  standard offpage *
  page75_i80
#ISCELL
  standard offpage *
  page75_i81
#ISCELL
  standard offpage *
  page75_i82
#ISCELL
  standard offpage *
  page75_i83
#ISCELL
  standard offpage *
  page75_i84
#CELL
  pure_quanta q_res *
  page75_i87
#ISCELL
  pure_quanta_power universal_power *
  page75_i88
#CELL
  pure_quanta q_res *
  page75_i89
#CELL
  pure_quanta q_res *
  page75_i9
#CELL
  pure_quanta q_res *
  page75_i90
#CELL
  pure_quanta q_res *
  page75_i91
#CELL
  pure_quanta q_res *
  page75_i92
#ISCELL
  standard offpage *
  page75_i93
#CELL
  pure_quanta q_res *
  page75_i94
#ISCELL
  pure_quanta_power universal_gnd *
  page75_i95
